# BASEBOARD_FAB2 (Tioga Pass) — schematic netlist excerpt (pin names and nets, part order shuffled) for the footprints in the layout excerpt that follows; sources: Cadence DE-HDL packaged netlist, KiCad conversion of Wiwynn_Tioga_Pass_MB.brd

C4P8  CAP_A  22.0UF 4V 20% X6S  pkg 0603V  page 42 : A = PVCCIO_CPU0 ; B = GND
R1W28  RES  0.0 5% CHIP  pkg 0402  page 191 : A = FM_PCH_PWRBTN_R1_N ; B = FM_PCH_PWRBTN_N
C2N2  CAP_A  1.0UF 6.3V 10% X6S  pkg 0402V  page 131 : A = P1V05_PCH_STBY ; B = GND

(kicad_pcb
	(version 20260206)
	(generator "pcbnew")
	(generator_version "10.0")
	(general
		(thickness 1.6)
		(legacy_teardrops no)
	)
	(paper "A4")
	(title_block
		(title "Wiwynn_Tioga_Pass_MB.brd")
		(comment 1 "Tioga Pass / footprints 2506-2508 of 4770")
	)
	(layers
		(0 "F.Cu" signal "TOP")
		(4 "In1.Cu" signal "L2GND")
		(6 "In2.Cu" signal "L3")
		(8 "In3.Cu" signal "L4GND")
		(10 "In4.Cu" signal "L5")
		(12 "In5.Cu" signal "L6GND")
		(14 "In6.Cu" signal "L7VCC")
		(16 "In7.Cu" signal "L8VCC")
		(18 "In8.Cu" signal "L9GND")
		(20 "In9.Cu" signal "L10")
		(22 "In10.Cu" signal "L11GND")
		(24 "In11.Cu" signal "L12")
		(26 "In12.Cu" signal "L13GND")
		(2 "B.Cu" signal "BOTTOM")
		(9 "F.Adhes" user "F.Adhesive")
		(11 "B.Adhes" user "B.Adhesive")
		(13 "F.Paste" user "Package Geometry/Pastemask Top")
		(15 "B.Paste" user "Package Geometry/Pastemask Bottom")
		(5 "F.SilkS" user "Ref Des/Silkscreen Top")
		(7 "B.SilkS" user "Ref Des/Silkscreen Bottom")
		(1 "F.Mask" user "Board Geometry/Soldermask Top")
		(3 "B.Mask" user "Board Geometry/Soldermask Bottom")
		(17 "Dwgs.User" user "User.Drawings")
		(19 "Cmts.User" user "User.Comments")
		(21 "Eco1.User" user "User.Eco1")
		(23 "Eco2.User" user "User.Eco2")
		(25 "Edge.Cuts" user "Board Geometry/Outline")
		(27 "Margin" user)
		(31 "F.CrtYd" user "Package Geometry/Place Bound Top")
		(29 "B.CrtYd" user "Package Geometry/Place Bound Bottom")
		(35 "F.Fab" user "Ref Des/Assembly Top")
		(33 "B.Fab" user "Ref Des/Assembly Bottom")
	)
	(footprint ""
		(layer "B.Cu")
		(at 391.73785 -111.05515 180)
		(property "Reference" "C2N2"
			(at 0 0 0)
			(layer "B.SilkS")
			(hide yes)
			(effects
				(font
					(size 1.27 1.27)
				)
				(justify mirror)
			)
		)
		(property "Value" ""
			(at 0 0 0)
			(layer "B.Fab")
			(effects
				(font
					(size 1.27 1.27)
				)
				(justify mirror)
			)
		)
		(duplicate_pad_numbers_are_jumpers no)
		(fp_rect
			(start 0.2794 0.9144)
			(end -0.2794 -0.1143)
			(stroke
				(width 0)
				(type default)
			)
			(fill no)
			(layer "B.CrtYd")
		)
		(fp_line
			(start 0.2794 0.9144)
			(end 0.2794 -0.1143)
			(stroke
				(width 0.1)
				(type default)
			)
			(layer "B.Fab")
		)
		(fp_line
			(start 0.2794 -0.1143)
			(end -0.2794 -0.1143)
			(stroke
				(width 0.1)
				(type default)
			)
			(layer "B.Fab")
		)
		(fp_line
			(start -0.2794 0.9144)
			(end 0.2794 0.9144)
			(stroke
				(width 0.1)
				(type default)
			)
			(layer "B.Fab")
		)
		(fp_line
			(start -0.2794 -0.1143)
			(end -0.2794 0.9144)
			(stroke
				(width 0.1)
				(type default)
			)
			(layer "B.Fab")
		)
		(pad "1" smd custom
			(at 0 0 90)
			(size 0.10414 0.10414)
			(layers "B.Cu" "B.Mask" "B.Paste")
			(net "P1V05_PCH_STBY")
			(options
				(clearance outline)
				(anchor circle)
			)
			(primitives
				(gr_poly
					(pts
						(xy -0.20828 -0.08636) (xy -0.20828 0.08636) (xy -0.08636 0.20828) (xy 0.086614 0.20828) (xy 0.20828 0.086614)
						(xy 0.20828 -0.08636) (xy 0.08636 -0.20828) (xy -0.08636 -0.20828)
					)
					(width 0)
					(fill yes)
				)
			)
		)
		(pad "2" smd custom
			(at 0 0.8001 90)
			(size 0.10414 0.10414)
			(layers "B.Cu" "B.Mask" "B.Paste")
			(net "GND")
			(options
				(clearance outline)
				(anchor circle)
			)
			(primitives
				(gr_poly
					(pts
						(xy -0.20828 -0.08636) (xy -0.20828 0.08636) (xy -0.08636 0.20828) (xy 0.086614 0.20828) (xy 0.20828 0.086614)
						(xy 0.20828 -0.08636) (xy 0.08636 -0.20828) (xy -0.08636 -0.20828)
					)
					(width 0)
					(fill yes)
				)
			)
		)
		(zone
			(layer "B.Cu")
			(hatch none 0.5)
			(connect_pads
				(clearance 0)
			)
			(min_thickness 0.25)
			(keepout
				(tracks not_allowed)
				(vias allowed)
				(pads allowed)
				(copperpour not_allowed)
				(footprints allowed)
			)
			(placement
				(enabled no)
				(sheetname "")
			)
			(fill
				(thermal_gap 0.5)
				(thermal_bridge_width 0.5)
				(island_removal_mode 0)
			)
			(polygon
				(pts
					(xy 391.65022 -111.2647) (xy 391.65022 -111.6457) (xy 391.82548 -111.6457) (xy 391.825734 -111.2647)
				)
			)
		)
		(zone
			(layer "B.Cu")
			(hatch none 0.5)
			(connect_pads
				(clearance 0)
			)
			(min_thickness 0.25)
			(keepout
				(tracks allowed)
				(vias not_allowed)
				(pads allowed)
				(copperpour not_allowed)
				(footprints allowed)
			)
			(placement
				(enabled no)
				(sheetname "")
			)
			(fill
				(thermal_gap 0.5)
				(thermal_bridge_width 0.5)
				(island_removal_mode 0)
			)
			(polygon
				(pts
					(xy 391.65022 -111.2647) (xy 391.65022 -111.6457) (xy 391.82548 -111.6457) (xy 391.825734 -111.2647)
				)
			)
		)
	)
	(footprint ""
		(layer "B.Cu")
		(at 370.334794 -68.048632)
		(property "Reference" "R1W28"
			(at 0.8382 -0.67818 0)
			(unlocked yes)
			(layer "B.SilkS")
			(effects
				(font
					(size 0.4064 0.254)
					(thickness 0.1524)
				)
				(justify left mirror)
			)
		)
		(property "Value" ""
			(at 0 0 0)
			(layer "B.Fab")
			(effects
				(font
					(size 1.27 1.27)
				)
				(justify mirror)
			)
		)
		(duplicate_pad_numbers_are_jumpers no)
		(fp_poly
			(pts
				(xy 0.2794 -0.1016) (xy -0.2794 -0.1016) (xy -0.2794 0.9906) (xy 0.2794 0.9906)
			)
			(stroke
				(width 0)
				(type default)
			)
			(fill no)
			(layer "B.CrtYd")
		)
		(fp_line
			(start -0.2794 -0.1016)
			(end 0.2794 -0.1016)
			(stroke
				(width 0.1)
				(type default)
			)
			(layer "B.Fab")
		)
		(fp_line
			(start -0.2794 0.9906)
			(end -0.2794 -0.1016)
			(stroke
				(width 0.1)
				(type default)
			)
			(layer "B.Fab")
		)
		(fp_line
			(start 0.2794 -0.1016)
			(end 0.2794 0.9906)
			(stroke
				(width 0.1)
				(type default)
			)
			(layer "B.Fab")
		)
		(fp_line
			(start 0.2794 0.9906)
			(end -0.2794 0.9906)
			(stroke
				(width 0.1)
				(type default)
			)
			(layer "B.Fab")
		)
		(pad "1" smd rect
			(at 0 0 180)
			(size 0.508 0.508)
			(layers "B.Cu" "B.Mask" "B.Paste")
			(net "FM_PCH_PWRBTN_R1_N")
		)
		(pad "2" smd rect
			(at 0 0.889 180)
			(size 0.508 0.508)
			(layers "B.Cu" "B.Mask" "B.Paste")
			(net "FM_PCH_PWRBTN_N")
		)
		(zone
			(layer "B.Cu")
			(hatch none 0.5)
			(connect_pads
				(clearance 0)
			)
			(min_thickness 0.25)
			(keepout
				(tracks allowed)
				(vias not_allowed)
				(pads allowed)
				(copperpour not_allowed)
				(footprints allowed)
			)
			(placement
				(enabled no)
				(sheetname "")
			)
			(fill
				(thermal_gap 0.5)
				(thermal_bridge_width 0.5)
				(island_removal_mode 0)
			)
			(polygon
				(pts
					(xy 370.588794 -67.794632) (xy 370.080794 -67.794632) (xy 370.080794 -67.413632) (xy 370.588794 -67.413632)
				)
			)
		)
		(zone
			(layer "B.Cu")
			(hatch none 0.5)
			(connect_pads
				(clearance 0)
			)
			(min_thickness 0.25)
			(keepout
				(tracks not_allowed)
				(vias allowed)
				(pads allowed)
				(copperpour not_allowed)
				(footprints allowed)
			)
			(placement
				(enabled no)
				(sheetname "")
			)
			(fill
				(thermal_gap 0.5)
				(thermal_bridge_width 0.5)
				(island_removal_mode 0)
			)
			(polygon
				(pts
					(xy 370.588794 -67.413632) (xy 370.080794 -67.413632) (xy 370.080794 -67.794632) (xy 370.588794 -67.794632)
				)
			)
		)
	)
	(footprint ""
		(layer "B.Cu")
		(at 280.354024 -71.841614 180)
		(property "Reference" "C4P8"
			(at 0 0 0)
			(layer "B.SilkS")
			(hide yes)
			(effects
				(font
					(size 1.27 1.27)
				)
				(justify mirror)
			)
		)
		(property "Value" ""
			(at 0 0 0)
			(layer "B.Fab")
			(effects
				(font
					(size 1.27 1.27)
				)
				(justify mirror)
			)
		)
		(duplicate_pad_numbers_are_jumpers no)
		(fp_poly
			(pts
				(xy 0.4953 -0.2032) (xy -0.4953 -0.2032) (xy -0.4953 1.6002) (xy 0.4953 1.6002)
			)
			(stroke
				(width 0)
				(type default)
			)
			(fill no)
			(layer "B.CrtYd")
		)
		(fp_line
			(start 0.4953 1.6002)
			(end 0.4953 -0.2032)
			(stroke
				(width 0.1)
				(type default)
			)
			(layer "B.Fab")
		)
		(fp_line
			(start 0.4953 -0.2032)
			(end -0.4953 -0.2032)
			(stroke
				(width 0.1)
				(type default)
			)
			(layer "B.Fab")
		)
		(fp_line
			(start -0.4953 1.6002)
			(end 0.4953 1.6002)
			(stroke
				(width 0.1)
				(type default)
			)
			(layer "B.Fab")
		)
		(fp_line
			(start -0.4953 -0.2032)
			(end -0.4953 1.6002)
			(stroke
				(width 0.1)
				(type default)
			)
			(layer "B.Fab")
		)
		(pad "1" smd rect
			(at 0 0)
			(size 0.762 0.889)
			(layers "B.Cu" "B.Mask" "B.Paste")
			(net "PVCCIO_CPU0")
		)
		(pad "2" smd rect
			(at 0 1.397)
			(size 0.762 0.889)
			(layers "B.Cu" "B.Mask" "B.Paste")
			(net "GND")
		)
		(zone
			(layer "B.Cu")
			(hatch none 0.5)
			(connect_pads
				(clearance 0)
			)
			(min_thickness 0.25)
			(keepout
				(tracks not_allowed)
				(vias allowed)
				(pads allowed)
				(copperpour not_allowed)
				(footprints allowed)
			)
			(placement
				(enabled no)
				(sheetname "")
			)
			(fill
				(thermal_gap 0.5)
				(thermal_bridge_width 0.5)
				(island_removal_mode 0)
			)
			(polygon
				(pts
					(xy 279.973024 -72.286114) (xy 280.735024 -72.286114) (xy 280.735024 -72.794114) (xy 279.973024 -72.794114)
				)
			)
		)
	)
)
